#ISCELL
  mstr_misc dns *
  *
#ISCELL
  pure_quanta quanta_title_block_c *
  *
#CELL
  pure_quanta q_res *
  page148_i244
#CELL
  pure_quanta q_res *
  page148_i245
#CELL
  pure_quanta q_res *
  page148_i246
#ISCELL
  pure_quanta_power universal_gnd *
  page148_i247
#ISCELL
  pure_quanta_power universal_power *
  page148_i248
#CELL
  pure_quanta q_res *
  page148_i249
#CELL
  pure_quanta q_res *
  page148_i250
#ISCELL
  standard offpage *
  page148_i251
#ISCELL
  standard offpage *
  page148_i252
#ISCELL
  standard offpage *
  page148_i253
#ISCELL
  standard offpage *
  page148_i254
#CELL
  pure_quanta q_res *
  page148_i255
#CELL
  pure_quanta q_res *
  page148_i256
#CELL
  pure_quanta q_res *
  page148_i257
#CELL
  pure_quanta q_res *
  page148_i258
#ISCELL
  pure_quanta_power universal_gnd *
  page148_i259
#ISCELL
  pure_quanta_power universal_power *
  page148_i260
#CELL
  pure_quanta q_res *
  page148_i261
#ISCELL
  standard offpage *
  page148_i262
#ISCELL
  standard offpage *
  page148_i263
#ISCELL
  standard offpage *
  page148_i264
#ISCELL
  standard offpage *
  page148_i265
#CELL
  pure_quanta 74hc4052pw *
  page148_i266
#ISCELL
  pure_quanta_power universal_gnd *
  page148_i267
#ISCELL
  pure_quanta_power universal_power *
  page148_i292
#CELL
  pure_quanta q_cap *
  page148_i293
#ISCELL
  pure_quanta_power universal_gnd *
  page148_i294
#ISCELL
  pure_quanta_power universal_power *
  page148_i295
#ISCELL
  standard offpage *
  page148_i296
#ISCELL
  standard offpage *
  page148_i297
#ISCELL
  pure_quanta_power universal_power *
  page148_i298
#CELL
  pure_quanta q_cap *
  page148_i299
#ISCELL
  pure_quanta_power universal_gnd *
  page148_i300
#ISCELL
  pure_quanta_power universal_gnd *
  page148_i301
#CELL
  pure_quanta 74hc4052pw *
  page148_i302
#CELL
  pure_quanta q_res *
  page148_i305
#CELL
  pure_quanta q_res *
  page148_i306
#ISCELL
  pure_quanta_power universal_gnd *
  page148_i307
#ISCELL
  pure_quanta_power universal_power *
  page148_i308
#CELL
  pure_quanta q_res *
  page148_i309
#CELL
  pure_quanta q_res *
  page148_i310
#ISCELL
  pure_quanta_power universal_gnd *
  page148_i311
#ISCELL
  standard offpage *
  page148_i312
#ISCELL
  standard offpage *
  page148_i313
#ISCELL
  standard offpage *
  page148_i314
#ISCELL
  standard offpage *
  page148_i315
#ISCELL
  standard offpage *
  page148_i327
#CELL
  pure_quanta q_res *
  page148_i329
#ISCELL
  standard offpage *
  page148_i331
#CELL
  pure_quanta q_res *
  page148_i332
#ISCELL
  standard offpage *
  page148_i336
#ISCELL
  pure_quanta_power universal_power *
  page148_i337
#CELL
  pure_quanta q_res *
  page148_i339
#CELL
  pure_quanta sn74lvc1g07dbvr *
  page148_i340
#ISCELL
  pure_quanta_power universal_power *
  page148_i341
#CELL
  pure_quanta q_cap *
  page148_i342
#ISCELL
  pure_quanta_power universal_gnd *
  page148_i343
#ISCELL
  pure_quanta_power universal_gnd *
  page148_i344
#ISCELL
  standard offpage *
  page148_i347
#CELL
  pure_quanta q_res *
  page148_i349
#ISCELL
  standard offpage *
  page148_i351
#CELL
  pure_quanta q_res *
  page148_i352
#ISCELL
  standard offpage *
  page148_i355
#CELL
  pure_quanta q_res *
  page148_i357
#ISCELL
  standard offpage *
  page148_i362
#CELL
  pure_quanta q_res *
  page148_i363
#ISCELL
  standard offpage *
  page148_i365
#CELL
  pure_quanta q_res *
  page148_i366
#ISCELL
  standard offpage *
  page148_i367
#CELL
  pure_quanta q_res *
  page148_i368
#CELL
  pure_quanta q_res *
  page148_i369
#ISCELL
  pure_quanta_power universal_gnd *
  page148_i370
#CELL
  pure_quanta q_res *
  page148_i371
#ISCELL
  pure_quanta_power universal_gnd *
  page148_i372
#CELL
  pure_quanta q_res *
  page148_i373
#ISCELL
  pure_quanta_power universal_gnd *
  page148_i374
